(kicad_pcb
	(version 20260206)
	(generator "pcbnew")
	(generator_version "10.0")
	(general
		(thickness 1.6)
		(legacy_teardrops no)
	)
	(paper "A4")
	(title_block
		(title "01162023_DA0F0TEBIF0_F0T_Expander_BD_F_brd_V02_OCP.brd")
		(comment 1 "Grand Teton / footprint 6619 of 9728 (PEX0), pads 713-833 of 2397")
	)
	(layers
		(0 "F.Cu" signal "TOP")
		(4 "In1.Cu" signal "GND")
		(6 "In2.Cu" signal "VCC")
		(8 "In3.Cu" signal "VCC1")
		(10 "In4.Cu" signal "GND1")
		(12 "In5.Cu" signal "IN1")
		(14 "In6.Cu" signal "GND2")
		(16 "In7.Cu" signal "IN2")
		(18 "In8.Cu" signal "GND3")
		(20 "In9.Cu" signal "IN3")
		(22 "In10.Cu" signal "GND4")
		(24 "In11.Cu" signal "IN4")
		(26 "In12.Cu" signal "GND5")
		(28 "In13.Cu" signal "IN5")
		(30 "In14.Cu" signal "GND6")
		(32 "In15.Cu" signal "IN6")
		(34 "In16.Cu" signal "GND7")
		(2 "B.Cu" signal "BOTTOM")
		(9 "F.Adhes" user "F.Adhesive")
		(11 "B.Adhes" user "B.Adhesive")
		(13 "F.Paste" user "Package Geometry/Pastemask Top")
		(15 "B.Paste" user "Package Geometry/Pastemask Bottom")
		(5 "F.SilkS" user "Ref Des/Silkscreen Top")
		(7 "B.SilkS" user "Ref Des/Silkscreen Bottom")
		(1 "F.Mask" user "Board Geometry/Soldermask Top")
		(3 "B.Mask" user "Board Geometry/Soldermask Bottom")
		(17 "Dwgs.User" user "User.Drawings")
		(19 "Cmts.User" user "User.Comments")
		(21 "Eco1.User" user "User.Eco1")
		(23 "Eco2.User" user "User.Eco2")
		(25 "Edge.Cuts" user "Board Geometry/Outline")
		(27 "Margin" user)
		(31 "F.CrtYd" user "Package Geometry/Place Bound Top")
		(29 "B.CrtYd" user "Package Geometry/Place Bound Bottom")
		(35 "F.Fab" user "Ref Des/Assembly Top")
		(33 "B.Fab" user "Ref Des/Assembly Bottom")
	)
	(footprint ""
		(layer "F.Cu")
		(at 59.649868 -295.89984)
		(property "Reference" "PEX0"
			(at -3.360166 35.566858 0)
			(unlocked yes)
			(layer "F.SilkS")
			(effects
				(font
					(size 2.032 1.524)
					(thickness 0.1524)
				)
				(justify left)
			)
		)
		(property "Value" ""
			(at 0 0 0)
			(layer "F.Fab")
			(effects
				(font
					(size 1.27 1.27)
				)
			)
		)
		(duplicate_pad_numbers_are_jumpers no)
		(pad "AP29" smd circle
			(at 3.800094 8.549894)
			(size 0.4572 0.4572)
			(layers "F.Cu" "F.Mask" "F.Paste")
			(net "P1V25_SERDES_VDDPLL_PEX0")
		)
		(pad "AP30" smd circle
			(at 4.750054 8.549894)
			(size 0.4572 0.4572)
			(layers "F.Cu" "F.Mask" "F.Paste")
			(net "P1V25_SERDES_VDDPLL_PEX0")
		)
		(pad "AP31" smd circle
			(at 5.700014 8.549894)
			(size 0.4572 0.4572)
			(layers "F.Cu" "F.Mask" "F.Paste")
			(net "P1V25_SERDES_VDDPLL_PEX0")
		)
		(pad "AP32" smd circle
			(at 6.649974 8.549894)
			(size 0.4572 0.4572)
			(layers "F.Cu" "F.Mask" "F.Paste")
			(net "P1V25_SERDES_VDDPLL_PEX0")
		)
		(pad "AP33" smd circle
			(at 7.599934 8.549894)
			(size 0.4572 0.4572)
			(layers "F.Cu" "F.Mask" "F.Paste")
			(net "P1V25_SERDES_VDDPLL_PEX0")
		)
		(pad "AP34" smd circle
			(at 8.549894 8.549894)
			(size 0.4572 0.4572)
			(layers "F.Cu" "F.Mask" "F.Paste")
			(net "GND")
		)
		(pad "AP35" smd circle
			(at 9.500108 8.549894)
			(size 0.4572 0.4572)
			(layers "F.Cu" "F.Mask" "F.Paste")
			(net "P1V8_VDDA_PEX0")
		)
		(pad "AP36" smd circle
			(at 10.450068 8.549894)
			(size 0.4572 0.4572)
			(layers "F.Cu" "F.Mask" "F.Paste")
			(net "Net_485")
		)
		(pad "AP37" smd circle
			(at 11.400028 8.549894)
			(size 0.4572 0.4572)
			(layers "F.Cu" "F.Mask" "F.Paste")
			(net "GND")
		)
		(pad "AP38" smd circle
			(at 12.349988 8.549894)
			(size 0.4572 0.4572)
			(layers "F.Cu" "F.Mask" "F.Paste")
			(net "Net_2898")
		)
		(pad "AP39" smd circle
			(at 13.299948 8.549894)
			(size 0.4572 0.4572)
			(layers "F.Cu" "F.Mask" "F.Paste")
			(net "Net_2904")
		)
		(pad "AP40" smd circle
			(at 14.249908 8.549894)
			(size 0.4572 0.4572)
			(layers "F.Cu" "F.Mask" "F.Paste")
			(net "GND")
		)
		(pad "AP41" smd circle
			(at 15.200122 8.549894)
			(size 0.4572 0.4572)
			(layers "F.Cu" "F.Mask" "F.Paste")
			(net "P5E_PEX0_STN0_TX_DP<1>")
		)
		(pad "AP42" smd circle
			(at 16.150082 8.549894)
			(size 0.4572 0.4572)
			(layers "F.Cu" "F.Mask" "F.Paste")
			(net "P5E_PEX0_STN0_TX_DN<1>")
		)
		(pad "AP43" smd circle
			(at 17.100042 8.549894)
			(size 0.4572 0.4572)
			(layers "F.Cu" "F.Mask" "F.Paste")
			(net "GND")
		)
		(pad "AP44" smd circle
			(at 18.050002 8.549894)
			(size 0.4572 0.4572)
			(layers "F.Cu" "F.Mask" "F.Paste")
			(net "GND")
		)
		(pad "AP45" smd circle
			(at 18.999962 8.549894)
			(size 0.4572 0.4572)
			(layers "F.Cu" "F.Mask" "F.Paste")
			(net "GND")
		)
		(pad "AP46" smd circle
			(at 19.949922 8.549894)
			(size 0.4572 0.4572)
			(layers "F.Cu" "F.Mask" "F.Paste")
			(net "GND")
		)
		(pad "AP47" smd circle
			(at 20.899882 8.549894)
			(size 0.4572 0.4572)
			(layers "F.Cu" "F.Mask" "F.Paste")
			(net "GND")
		)
		(pad "AP48" smd circle
			(at 21.850096 8.549894)
			(size 0.4572 0.4572)
			(layers "F.Cu" "F.Mask" "F.Paste")
			(net "P5E_PEX0_STN0_RX_DP<1>")
		)
		(pad "AP49" smd circle
			(at 22.800056 8.549894)
			(size 0.4572 0.4572)
			(layers "F.Cu" "F.Mask" "F.Paste")
			(net "P5E_PEX0_STN0_RX_DN<1>")
		)
		(pad "AR1" smd circle
			(at -22.800056 9.500108)
			(size 0.4572 0.4572)
			(layers "F.Cu" "F.Mask" "F.Paste")
			(net "GND")
		)
		(pad "AR2" smd circle
			(at -21.850096 9.500108)
			(size 0.4572 0.4572)
			(layers "F.Cu" "F.Mask" "F.Paste")
			(net "GND")
		)
		(pad "AR3" smd circle
			(at -20.899882 9.500108)
			(size 0.4572 0.4572)
			(layers "F.Cu" "F.Mask" "F.Paste")
			(net "Net_2711")
		)
		(pad "AR4" smd circle
			(at -19.949922 9.500108)
			(size 0.4572 0.4572)
			(layers "F.Cu" "F.Mask" "F.Paste")
			(net "Net_2725")
		)
		(pad "AR5" smd circle
			(at -18.999962 9.500108)
			(size 0.4572 0.4572)
			(layers "F.Cu" "F.Mask" "F.Paste")
			(net "GND")
		)
		(pad "AR6" smd circle
			(at -18.050002 9.500108)
			(size 0.4572 0.4572)
			(layers "F.Cu" "F.Mask" "F.Paste")
			(net "Net_2739")
		)
		(pad "AR7" smd circle
			(at -17.100042 9.500108)
			(size 0.4572 0.4572)
			(layers "F.Cu" "F.Mask" "F.Paste")
			(net "Net_2753")
		)
		(pad "AR8" smd circle
			(at -16.150082 9.500108)
			(size 0.4572 0.4572)
			(layers "F.Cu" "F.Mask" "F.Paste")
			(net "GND")
		)
		(pad "AR9" smd circle
			(at -15.200122 9.500108)
			(size 0.4572 0.4572)
			(layers "F.Cu" "F.Mask" "F.Paste")
			(net "GND")
		)
		(pad "AR10" smd circle
			(at -14.249908 9.500108)
			(size 0.4572 0.4572)
			(layers "F.Cu" "F.Mask" "F.Paste")
			(net "GND")
		)
		(pad "AR11" smd circle
			(at -13.299948 9.500108)
			(size 0.4572 0.4572)
			(layers "F.Cu" "F.Mask" "F.Paste")
			(net "GND")
		)
		(pad "AR12" smd circle
			(at -12.349988 9.500108)
			(size 0.4572 0.4572)
			(layers "F.Cu" "F.Mask" "F.Paste")
			(net "GND")
		)
		(pad "AR13" smd circle
			(at -11.400028 9.500108)
			(size 0.4572 0.4572)
			(layers "F.Cu" "F.Mask" "F.Paste")
			(net "GND")
		)
		(pad "AR14" smd circle
			(at -10.450068 9.500108)
			(size 0.4572 0.4572)
			(layers "F.Cu" "F.Mask" "F.Paste")
			(net "GND")
		)
		(pad "AR15" smd circle
			(at -9.500108 9.500108)
			(size 0.4572 0.4572)
			(layers "F.Cu" "F.Mask" "F.Paste")
			(net "GND")
		)
		(pad "AR16" smd circle
			(at -8.549894 9.500108)
			(size 0.4572 0.4572)
			(layers "F.Cu" "F.Mask" "F.Paste")
			(net "GND")
		)
		(pad "AR17" smd circle
			(at -7.599934 9.500108)
			(size 0.4572 0.4572)
			(layers "F.Cu" "F.Mask" "F.Paste")
			(net "GND")
		)
		(pad "AR18" smd circle
			(at -6.649974 9.500108)
			(size 0.4572 0.4572)
			(layers "F.Cu" "F.Mask" "F.Paste")
			(net "GND")
		)
		(pad "AR19" smd circle
			(at -5.700014 9.500108)
			(size 0.4572 0.4572)
			(layers "F.Cu" "F.Mask" "F.Paste")
			(net "GND")
		)
		(pad "AR20" smd circle
			(at -4.750054 9.500108)
			(size 0.4572 0.4572)
			(layers "F.Cu" "F.Mask" "F.Paste")
			(net "GND")
		)
		(pad "AR21" smd circle
			(at -3.800094 9.500108)
			(size 0.4572 0.4572)
			(layers "F.Cu" "F.Mask" "F.Paste")
			(net "GND")
		)
		(pad "AR22" smd circle
			(at -2.84988 9.500108)
			(size 0.4572 0.4572)
			(layers "F.Cu" "F.Mask" "F.Paste")
			(net "GND")
		)
		(pad "AR23" smd circle
			(at -1.89992 9.500108)
			(size 0.4572 0.4572)
			(layers "F.Cu" "F.Mask" "F.Paste")
			(net "GND")
		)
		(pad "AR24" smd circle
			(at -0.94996 9.500108)
			(size 0.4572 0.4572)
			(layers "F.Cu" "F.Mask" "F.Paste")
			(net "GND")
		)
		(pad "AR25" smd circle
			(at 0 9.500108)
			(size 0.4572 0.4572)
			(layers "F.Cu" "F.Mask" "F.Paste")
			(net "GND")
		)
		(pad "AR26" smd circle
			(at 0.94996 9.500108)
			(size 0.4572 0.4572)
			(layers "F.Cu" "F.Mask" "F.Paste")
			(net "GND")
		)
		(pad "AR27" smd circle
			(at 1.89992 9.500108)
			(size 0.4572 0.4572)
			(layers "F.Cu" "F.Mask" "F.Paste")
			(net "GND")
		)
		(pad "AR28" smd circle
			(at 2.84988 9.500108)
			(size 0.4572 0.4572)
			(layers "F.Cu" "F.Mask" "F.Paste")
			(net "GND")
		)
		(pad "AR29" smd circle
			(at 3.800094 9.500108)
			(size 0.4572 0.4572)
			(layers "F.Cu" "F.Mask" "F.Paste")
			(net "GND")
		)
		(pad "AR30" smd circle
			(at 4.750054 9.500108)
			(size 0.4572 0.4572)
			(layers "F.Cu" "F.Mask" "F.Paste")
			(net "GND")
		)
		(pad "AR31" smd circle
			(at 5.700014 9.500108)
			(size 0.4572 0.4572)
			(layers "F.Cu" "F.Mask" "F.Paste")
			(net "GND")
		)
		(pad "AR32" smd circle
			(at 6.649974 9.500108)
			(size 0.4572 0.4572)
			(layers "F.Cu" "F.Mask" "F.Paste")
			(net "GND")
		)
		(pad "AR33" smd circle
			(at 7.599934 9.500108)
			(size 0.4572 0.4572)
			(layers "F.Cu" "F.Mask" "F.Paste")
			(net "GND")
		)
		(pad "AR34" smd circle
			(at 8.549894 9.500108)
			(size 0.4572 0.4572)
			(layers "F.Cu" "F.Mask" "F.Paste")
			(net "GND")
		)
		(pad "AR35" smd circle
			(at 9.500108 9.500108)
			(size 0.4572 0.4572)
			(layers "F.Cu" "F.Mask" "F.Paste")
			(net "GND")
		)
		(pad "AR36" smd circle
			(at 10.450068 9.500108)
			(size 0.4572 0.4572)
			(layers "F.Cu" "F.Mask" "F.Paste")
			(net "Net_483")
		)
		(pad "AR37" smd circle
			(at 11.400028 9.500108)
			(size 0.4572 0.4572)
			(layers "F.Cu" "F.Mask" "F.Paste")
			(net "GND")
		)
		(pad "AR38" smd circle
			(at 12.349988 9.500108)
			(size 0.4572 0.4572)
			(layers "F.Cu" "F.Mask" "F.Paste")
			(net "Net_2903")
		)
		(pad "AR39" smd circle
			(at 13.299948 9.500108)
			(size 0.4572 0.4572)
			(layers "F.Cu" "F.Mask" "F.Paste")
			(net "Net_2905")
		)
		(pad "AR40" smd circle
			(at 14.249908 9.500108)
			(size 0.4572 0.4572)
			(layers "F.Cu" "F.Mask" "F.Paste")
			(net "GND")
		)
		(pad "AR41" smd circle
			(at 15.200122 9.500108)
			(size 0.4572 0.4572)
			(layers "F.Cu" "F.Mask" "F.Paste")
			(net "GND")
		)
		(pad "AR42" smd circle
			(at 16.150082 9.500108)
			(size 0.4572 0.4572)
			(layers "F.Cu" "F.Mask" "F.Paste")
			(net "GND")
		)
		(pad "AR43" smd circle
			(at 17.100042 9.500108)
			(size 0.4572 0.4572)
			(layers "F.Cu" "F.Mask" "F.Paste")
			(net "P5E_PEX0_STN0_TX_DP<2>")
		)
		(pad "AR44" smd circle
			(at 18.050002 9.500108)
			(size 0.4572 0.4572)
			(layers "F.Cu" "F.Mask" "F.Paste")
			(net "P5E_PEX0_STN0_TX_DN<2>")
		)
		(pad "AR45" smd circle
			(at 18.999962 9.500108)
			(size 0.4572 0.4572)
			(layers "F.Cu" "F.Mask" "F.Paste")
			(net "GND")
		)
		(pad "AR46" smd circle
			(at 19.949922 9.500108)
			(size 0.4572 0.4572)
			(layers "F.Cu" "F.Mask" "F.Paste")
			(net "P5E_PEX0_STN0_RX_DP<2>")
		)
		(pad "AR47" smd circle
			(at 20.899882 9.500108)
			(size 0.4572 0.4572)
			(layers "F.Cu" "F.Mask" "F.Paste")
			(net "P5E_PEX0_STN0_RX_DN<2>")
		)
		(pad "AR48" smd circle
			(at 21.850096 9.500108)
			(size 0.4572 0.4572)
			(layers "F.Cu" "F.Mask" "F.Paste")
			(net "GND")
		)
		(pad "AR49" smd circle
			(at 22.800056 9.500108)
			(size 0.4572 0.4572)
			(layers "F.Cu" "F.Mask" "F.Paste")
			(net "GND")
		)
		(pad "AT1" smd circle
			(at -22.800056 10.450068)
			(size 0.4572 0.4572)
			(layers "F.Cu" "F.Mask" "F.Paste")
			(net "Net_2712")
		)
		(pad "AT2" smd circle
			(at -21.850096 10.450068)
			(size 0.4572 0.4572)
			(layers "F.Cu" "F.Mask" "F.Paste")
			(net "Net_2726")
		)
		(pad "AT3" smd circle
			(at -20.899882 10.450068)
			(size 0.4572 0.4572)
			(layers "F.Cu" "F.Mask" "F.Paste")
			(net "GND")
		)
		(pad "AT4" smd circle
			(at -19.949922 10.450068)
			(size 0.4572 0.4572)
			(layers "F.Cu" "F.Mask" "F.Paste")
			(net "GND")
		)
		(pad "AT5" smd circle
			(at -18.999962 10.450068)
			(size 0.4572 0.4572)
			(layers "F.Cu" "F.Mask" "F.Paste")
			(net "GND")
		)
		(pad "AT6" smd circle
			(at -18.050002 10.450068)
			(size 0.4572 0.4572)
			(layers "F.Cu" "F.Mask" "F.Paste")
			(net "GND")
		)
		(pad "AT7" smd circle
			(at -17.100042 10.450068)
			(size 0.4572 0.4572)
			(layers "F.Cu" "F.Mask" "F.Paste")
			(net "GND")
		)
		(pad "AT8" smd circle
			(at -16.150082 10.450068)
			(size 0.4572 0.4572)
			(layers "F.Cu" "F.Mask" "F.Paste")
			(net "Net_2740")
		)
		(pad "AT9" smd circle
			(at -15.200122 10.450068)
			(size 0.4572 0.4572)
			(layers "F.Cu" "F.Mask" "F.Paste")
			(net "Net_2754")
		)
		(pad "AT10" smd circle
			(at -14.249908 10.450068)
			(size 0.4572 0.4572)
			(layers "F.Cu" "F.Mask" "F.Paste")
			(net "GND")
		)
		(pad "AT11" smd circle
			(at -13.299948 10.450068)
			(size 0.4572 0.4572)
			(layers "F.Cu" "F.Mask" "F.Paste")
			(net "GND")
		)
		(pad "AT12" smd circle
			(at -12.349988 10.450068)
			(size 0.4572 0.4572)
			(layers "F.Cu" "F.Mask" "F.Paste")
			(net "GND")
		)
		(pad "AT13" smd circle
			(at -11.400028 10.450068)
			(size 0.4572 0.4572)
			(layers "F.Cu" "F.Mask" "F.Paste")
			(net "GND")
		)
		(pad "AT14" smd circle
			(at -10.450068 10.450068)
			(size 0.4572 0.4572)
			(layers "F.Cu" "F.Mask" "F.Paste")
			(net "GND")
		)
		(pad "AT15" smd circle
			(at -9.500108 10.450068)
			(size 0.4572 0.4572)
			(layers "F.Cu" "F.Mask" "F.Paste")
			(net "GND")
		)
		(pad "AT16" smd circle
			(at -8.549894 10.450068)
			(size 0.4572 0.4572)
			(layers "F.Cu" "F.Mask" "F.Paste")
			(net "GND")
		)
		(pad "AT17" smd circle
			(at -7.599934 10.450068)
			(size 0.4572 0.4572)
			(layers "F.Cu" "F.Mask" "F.Paste")
			(net "GND")
		)
		(pad "AT18" smd circle
			(at -6.649974 10.450068)
			(size 0.4572 0.4572)
			(layers "F.Cu" "F.Mask" "F.Paste")
			(net "GND")
		)
		(pad "AT19" smd circle
			(at -5.700014 10.450068)
			(size 0.4572 0.4572)
			(layers "F.Cu" "F.Mask" "F.Paste")
			(net "GND")
		)
		(pad "AT20" smd circle
			(at -4.750054 10.450068)
			(size 0.4572 0.4572)
			(layers "F.Cu" "F.Mask" "F.Paste")
			(net "GND")
		)
		(pad "AT21" smd circle
			(at -3.800094 10.450068)
			(size 0.4572 0.4572)
			(layers "F.Cu" "F.Mask" "F.Paste")
			(net "GND")
		)
		(pad "AT22" smd circle
			(at -2.84988 10.450068)
			(size 0.4572 0.4572)
			(layers "F.Cu" "F.Mask" "F.Paste")
			(net "GND")
		)
		(pad "AT23" smd circle
			(at -1.89992 10.450068)
			(size 0.4572 0.4572)
			(layers "F.Cu" "F.Mask" "F.Paste")
			(net "GND")
		)
		(pad "AT24" smd circle
			(at -0.94996 10.450068)
			(size 0.4572 0.4572)
			(layers "F.Cu" "F.Mask" "F.Paste")
			(net "GND")
		)
		(pad "AT25" smd circle
			(at 0 10.450068)
			(size 0.4572 0.4572)
			(layers "F.Cu" "F.Mask" "F.Paste")
			(net "GND")
		)
		(pad "AT26" smd circle
			(at 0.94996 10.450068)
			(size 0.4572 0.4572)
			(layers "F.Cu" "F.Mask" "F.Paste")
			(net "GND")
		)
		(pad "AT27" smd circle
			(at 1.89992 10.450068)
			(size 0.4572 0.4572)
			(layers "F.Cu" "F.Mask" "F.Paste")
			(net "GND")
		)
		(pad "AT28" smd circle
			(at 2.84988 10.450068)
			(size 0.4572 0.4572)
			(layers "F.Cu" "F.Mask" "F.Paste")
			(net "GND")
		)
		(pad "AT29" smd circle
			(at 3.800094 10.450068)
			(size 0.4572 0.4572)
			(layers "F.Cu" "F.Mask" "F.Paste")
			(net "GND")
		)
		(pad "AT30" smd circle
			(at 4.750054 10.450068)
			(size 0.4572 0.4572)
			(layers "F.Cu" "F.Mask" "F.Paste")
			(net "GND")
		)
		(pad "AT31" smd circle
			(at 5.700014 10.450068)
			(size 0.4572 0.4572)
			(layers "F.Cu" "F.Mask" "F.Paste")
			(net "GND")
		)
		(pad "AT32" smd circle
			(at 6.649974 10.450068)
			(size 0.4572 0.4572)
			(layers "F.Cu" "F.Mask" "F.Paste")
			(net "GND")
		)
		(pad "AT33" smd circle
			(at 7.599934 10.450068)
			(size 0.4572 0.4572)
			(layers "F.Cu" "F.Mask" "F.Paste")
			(net "GND")
		)
		(pad "AT34" smd circle
			(at 8.549894 10.450068)
			(size 0.4572 0.4572)
			(layers "F.Cu" "F.Mask" "F.Paste")
			(net "GND")
		)
		(pad "AT35" smd circle
			(at 9.500108 10.450068)
			(size 0.4572 0.4572)
			(layers "F.Cu" "F.Mask" "F.Paste")
			(net "GND")
		)
		(pad "AT36" smd circle
			(at 10.450068 10.450068)
			(size 0.4572 0.4572)
			(layers "F.Cu" "F.Mask" "F.Paste")
			(net "Net_492")
		)
		(pad "AT37" smd circle
			(at 11.400028 10.450068)
			(size 0.4572 0.4572)
			(layers "F.Cu" "F.Mask" "F.Paste")
			(net "GND")
		)
		(pad "AT38" smd circle
			(at 12.349988 10.450068)
			(size 0.4572 0.4572)
			(layers "F.Cu" "F.Mask" "F.Paste")
			(net "Net_2869")
		)
		(pad "AT39" smd circle
			(at 13.299948 10.450068)
			(size 0.4572 0.4572)
			(layers "F.Cu" "F.Mask" "F.Paste")
			(net "Net_2854")
		)
		(pad "AT40" smd circle
			(at 14.249908 10.450068)
			(size 0.4572 0.4572)
			(layers "F.Cu" "F.Mask" "F.Paste")
			(net "GND")
		)
		(pad "AT41" smd circle
			(at 15.200122 10.450068)
			(size 0.4572 0.4572)
			(layers "F.Cu" "F.Mask" "F.Paste")
			(net "P5E_PEX0_STN0_TX_DP<3>")
		)
		(pad "AT42" smd circle
			(at 16.150082 10.450068)
			(size 0.4572 0.4572)
			(layers "F.Cu" "F.Mask" "F.Paste")
			(net "P5E_PEX0_STN0_TX_DN<3>")
		)
		(pad "AT43" smd circle
			(at 17.100042 10.450068)
			(size 0.4572 0.4572)
			(layers "F.Cu" "F.Mask" "F.Paste")
			(net "GND")
		)
		(pad "AT44" smd circle
			(at 18.050002 10.450068)
			(size 0.4572 0.4572)
			(layers "F.Cu" "F.Mask" "F.Paste")
			(net "GND")
		)
		(pad "AT45" smd circle
			(at 18.999962 10.450068)
			(size 0.4572 0.4572)
			(layers "F.Cu" "F.Mask" "F.Paste")
			(net "GND")
		)
		(pad "AT46" smd circle
			(at 19.949922 10.450068)
			(size 0.4572 0.4572)
			(layers "F.Cu" "F.Mask" "F.Paste")
			(net "GND")
		)
		(pad "AT47" smd circle
			(at 20.899882 10.450068)
			(size 0.4572 0.4572)
			(layers "F.Cu" "F.Mask" "F.Paste")
			(net "GND")
		)
		(pad "AT48" smd circle
			(at 21.850096 10.450068)
			(size 0.4572 0.4572)
			(layers "F.Cu" "F.Mask" "F.Paste")
			(net "P5E_PEX0_STN0_RX_DP<3>")
		)
		(pad "AT49" smd circle
			(at 22.800056 10.450068)
			(size 0.4572 0.4572)
			(layers "F.Cu" "F.Mask" "F.Paste")
			(net "P5E_PEX0_STN0_RX_DN<3>")
		)
		(pad "AU1" smd circle
			(at -22.800056 11.400028)
			(size 0.4572 0.4572)
			(layers "F.Cu" "F.Mask" "F.Paste")
			(net "GND")
		)
		(pad "AU2" smd circle
			(at -21.850096 11.400028)
			(size 0.4572 0.4572)
			(layers "F.Cu" "F.Mask" "F.Paste")
			(net "GND")
		)
	)
)
